                    - SPARES  LIST -

FET_N_DUAL_SMLF-2N7002DW,FET,DA
    Q6W2  2

                    - PART SUMMARY -

0R2J-L-GP_SMD-RG5-0R2J-L-GP,63A		1
0R3J-0-U-GP_RCL_GP-0R3J-0-U-GPA		2
120R2F-GP_RCL_GP-120R2F-GP,64.A		53
21K5R2F-GP_RCL_GP-21K5R2F-GP,6A		1
232KR2F-2-GP_SMD-RG1-232KR2F-2A		1
3D01R5F-GP_SMD-RG5-3D01R5F-GP,A		24
47KR2F-GP_RCL_GP-47KR2F-GP,64.A		1
4K42R2F-GP_SMD-RG-4K42R2F-GP,6A		1
5K1R2F-2-GP_SMD-RG-5K1R2F-2-GPA		1
74CBTLV1G125_SMLF-IC,C88177-00A	C88177-001	7
82K5R2F-GP_SMD-RG-82K5R2F-GP,6A		1
ADC128D818_SM-IC,H63642-001	H63642-001	1
ADM1085_SMT-IC,H46130-001	H46130-001	1
ADM1278_SM-IC,G99251-001	G99251-001	1
ADM4073_SM-EMPTY,G12194-001	G12194-001	2
ADM809_SMLF-IC,D23047-001-GND=A	D23047-001	2
AST2520A1-GP-GP_ASIC2-GB1-AST2A		1
AT24C64_SOICLF-IC,C47049-001-GA	C47049-001	2
BATTERY_PLCLF-202168-001	202168-001	1
CAPP_2626-270UF,16V,20%,OSCON,A	A31228-047	9
CAPP_3018-470UF,2.5V,20%,ALUM,A	699013-049	46
CAPP_3018-470UF,6.3V,20%,POSCAA	724613-091	3
CAPP_3018-68UF,16V,20%,TANT,72A	724613-112	16
CAPP_4040LF-470UF,16V,20%,ALUMA	A93539-036	4
CAPP_7343-220UF,4V,20%,POSCAP,A	724613-067	4
CAPP_7343HLF-330UF,10V,20%,POSA	724613-043	1
CAPP_7343LF-330UF,6.3V,20%,POSA	724613-042	4
CAPP_SM-470UF,2V,20%,ALUM,6990A	699013-031	8
CAPTIVE_SCREW_TH-HDW,H57868-001	H57868-001	1
CAP_0402-0.027UF,16V,10%,X7R,AA	A36096-129	4
CAP_0402-0.047UF,25V,10%,X7R,AA	A36096-090	1
CAP_0402-0.1UF,16V,10%,EMPTY,AA	A36096-030	3
CAP_0402-0.220UF,16V,10%,X7R,AA	A36096-104	24
CAP_0402-0.22UF,16V,10%,EMPTY,A	A36096-155	16
CAP_0402-0.22UF,16V,10%,X7R,A3A	A36096-155	224
CAP_0402-1.0UF,16V,10%,X6S,D97A	D97712-011	76
CAP_0402-1.0UF,16V,10%,X7S,G71A	G71842-007	1
CAP_0402-1.0UF,6.3V,10%,X6S,D9A	D97712-004	29
CAP_0402LF-0.01UF,25V,10%,X7R,A	A36096-045	3
CAP_0402LF-0.022UF,16V,10%,X7RA	A36096-073	1
CAP_0402LF-0.039UF,25V,10%,X7RA	A36096-063	1
CAP_0402LF-0.1UF,16V,10%,X7R,AA	A36096-030	6
CAP_0402LF-10.0PF,50V,5%,COG,AA	A36094-025	1
CAP_0402LF-100.0PF,50V,5%,COG,A	A36095-026	5
CAP_0402LF-1000PF,50V,10%,EMPTA	A36096-046	14
CAP_0402LF-1000PF,50V,10%,X7R,A	A36096-046	56
CAP_0402LF-12.0PF,50V,5%,COG,AA	A36095-043	2
CAP_0402LF-15.0PF,50V,5%,COG,AA	A36095-047	2
CAP_0402LF-18PF,50V,5%,C0G,A36A	A36095-042	2
CAP_0402LF-22.0PF,50V,5%,COG,AA	A36095-030	2
CAP_0402LF-2200PF,50V,10%,X7R,A	A36096-075	9
CAP_0402LF-220PF,50V,10%,X7R,AA	A36096-050	20
CAP_0402LF-27.0PF,50V,5%,COG,AA	A36095-038	2
CAP_0402LF-270PF,50V,10%,X7R,AA	A36096-065	1
CAP_0402LF-33.0PF,50V,5%,COG,AA	A36095-031	2
CAP_0402LF-3300PF,50V,10%,EMPTA	A36096-091	5
CAP_0402LF-47.0PF,50V,5%,COG,AA	A36095-025	7
CAP_0402LF-47.0PF,50V,5%,EMPTYA	A36095-025	2
CAP_0402LF-4700PF,50V,10%,EMPTA	A36096-066	4
CAP_0402LF-470PF,50V,10%,EMPTYA	A36096-049	2
CAP_0402LF-470PF,50V,10%,X7R,AA	A36096-049	4
CAP_0603-10UF,6.3V,20%,X6S,E15A	E15431-002	25
CAP_0603-4.7UF,6.3V,10%,X6S,E1A	E15431-003	9
CAP_0603LF-0.033UF,50V,10%,X7RA	603269-064	1
CAP_0603LF-0.1UF,25V,10%,X7R,6A	602433-020	7
CAP_0603LF-10UF,4V,20%,X6S,E15A	E15431-001	89
CAP_0805-100UF,4V,20%,X5R,6024A	602433-112	40
CAP_0805-10UF,16V,10%,X6S,C953A	C95333-007	108
CAP_0805-10UF,16V,10%,X7R,G106A	G10601-001	14
CAP_0805-22UF,6.3V,20%,X6S,C95A	C95333-008	7
CAP_0805-47UF,4V,20%,X6S,C9533A	C95333-006	109
CAP_0805LF-22UF,4V,20%,X6S,C95A	C95333-002	31
CAP_1206-0.068UF,50V,20%,X7R,1A	108427-047	1
CAP_1206LF-22UF,16V,10%,X6S,D3A	D38464-005	3
CAP_1210-100UF,16V,20%,X5R,644A	644066-127	7
CAP_1210-47UF,16V,20%,EMPTY,D3A	D38464-007	2
CAP_1210-47UF,16V,20%,X6S,D384A	D38464-007	12
CAP_A_0402V-0.01UF,25V,10%,EMPA	A36096-045	4
CAP_A_0402V-0.01UF,25V,10%,X7RA	A36096-045	106
CAP_A_0402V-0.1UF,16V,10%,EMPTA	A36096-030	12
CAP_A_0402V-0.1UF,16V,10%,X7R,A	A36096-030	262
CAP_A_0402V-1.0UF,6.3V,10%,X6SA	D97712-004	134
CAP_A_0603V-22.0UF,4V,20%,EMPTA	E15431-004	2
CAP_A_0603V-22.0UF,4V,20%,X6S,A	E15431-004	391
CAP_A_0603V-47UF,4V,20%,X5R,60A	602433-106	52
CHOKE_4PIN_SMLF-90 OHM,EMPTY,7A	752402-015	1
CONN12_C73564003_PIP-CONN,C735A	C73564-003	3
CONN12_G98257001_THMT-CONN,G98A	G98257-001	2
CONN14_H54902001_PIP-CONN,H549A	H54902-001	1
CONN17_H71061002_PIP1-CONN,H71A	H71061-002	1
CONN36_G97614001_CP-CONN,G9761A	G97614-001	1
CONN3_C95678002_PIP-CONN,C9567A	C95678-002	4
CONN3_G98259001_PIP-CONN,G9825A	G98259-001	1
CONN4_D42317002_PIP-CONN,D4231A	D42317-002	1
CONN4_H73295001_PIP-CONN,H7329A	H73295-001	1
CONN4_H73295001_PIP-EMPTY,H732A	H73295-001	1
CONN6_C74770005_PIP-HDR,C74770A	C74770-005	2
CONN72_G97614002_A_CP-CONN,G97A	G97614-002	1
CONN76_H22707001_THMT1-CONN,H2A	H22707-001	2
CONN7_E82125014_PIP_TH-CONN,E8A	E82125-014	1
CONN7_E82125014_PIP_TH-EMPTY,EA	E82125-014	1
CONN8_C77962004_PIP-CONN,C7796A	C77962-004	1
CONN8_H62179001_PIP-CONN,H6217A	H62179-001	1
CONN9_H51826001_PIP2-CONN,H518A	H51826-001	1
CRYSTAL_2013-25.000MHZ,IC,D717A	D71700-057	1
CRYSTAL_2013-25.000MHZ,IC,H196A	H19611-001	1
CRYSTAL_2013-48.000MHZ,IC,D717A	D71700-058	1
CRYSTAL_2013LF-25.000MHZ,IC,D7B	D71700-033	1
CRYSTAL_SM-24.000MHZ,IC,D95126A	D95126-001	1
CRYSTAL_SM-32.768KHZ,IC,C13544A	C13544-023	1
CSD87384M_SM-IC,H66258-001	H66258-001	1
DIODE2A_DUAL_SMLF-BAS70-05,DIOA	C90169-001	1
DIODEAC_DUAL_ARRAY_SM9-ESD3V3UA	G18435-001	1
DIODE_SM-1N4148W,IC,D89194-001	D89194-001	4
DIODE_SM-MBRS340T3G,EMPTY,C819A	C81983-002	1
DIODE_SM-SDMK0340L,EMPTY,H7179A	H71799-001	2
DIODE_SM-SDMK0340L,IC,H71799-0A	H71799-001	6
DIODE_SMLF-1N5819HW,IC,D55839-A	D55839-001	1
DIODE_SMLF-BAT54WS,IC,C73510-0A	C73510-001	4
FERRITE_SM-120,FB,693286-027	693286-027	6
FERRITE_SM-22,FB,656554-051	656554-051	6
FERRITE_SMLF-30,FB,693286-021	693286-021	2
FERRITE_SMLF-60,FB,693286-001	693286-001	1
FERRITE_SMLF-600,FB,656554-043	656554-043	2
FET_N_DUAL_SMLF-2N7002DW,FET,DA	D24280-001	4
FET_N_DUAL_SMLF-NTJD4001N,FET,A	E40049-001	15
FET_N_SOT23-2N7002,FET,C79254-A	C79254-001	6
FET_N_SOT23LF-2N7002,FET,C7925A	C79254-001	10
FSA3357_SM-IC,C63273-001	C63273-001	2
FUSE_SM-IC,C94311-016	C94311-016	1
FUSE_SMLF-IC,C94311-006	C94311-006	1
FUSE_SMT-IC,H45581-001	H45581-001	1
GTL2014_SM-IC,D66151-001	D66151-001	6
H5AN4G6NAFR-TFC-GP_MEMORY-G2-HA		1
HCB1608KF-800T30-GP_DISCRET-G9A		6
ICS9FGP204_MLFP-IC,E95226-001	E95226-001	1
INDUCTOR_SM-0.12UH,IND,D92183-A	D92183-034	18
INDUCTOR_SM-0.3UH,IND,D92183-0A	D92183-036	4
INDUCTOR_SM-0.47UH,IND,E13358-A	E13358-018	4
INDUCTOR_SM-1.00UH,IND,E98679-A	E98679-006	1
INDUCTOR_SM-100NH,IND,D92183-0A	D92183-019	2
INDUCTOR_SM-100NH,IND,D92183-0B	D92183-020	5
INDUCTOR_SM-150NH,IND,D92183-0A	D92183-021	2
INDUCTOR_SM-2.2UH,IND,E98761-0A	E98761-003	1
INDUCTOR_SMT-0.022UH,IND,72189A	721891-082	1
IR354XX_SM-IR35411,IC,H73688-0A	H73688-001	18
IR354XX_SM-IR35412,IC,H73684-0A	H73684-001	6
LBG_CORE_QAT_EXT_D_BGA1-IC,H91A	H91415-002	1
LCMXO2_A_256BGA-IC,H63395-001	H63395-001	1
LED_1NC-BLUE,IC,C96565-012	C96565-012	1
LED_1NCLF-GREEN,IC,C96565-011	C96565-011	1
LED_1NCLF-YELLOW,IC,C96565-003	C96565-003	1
LED_A1-RED,IC,D14725-005	D14725-005	1
LED_A1LF-GREEN,IC,C97278-010	C97278-010	3
LED_A1LF-GREEN,IC,D14725-022	D14725-022	2
LMV331IDCKRG4-GP_DISCRET-G-LMVA		1
M25PE16_SM-IC,H77797-001	H77797-001	1
MAX9634_SOT-IC,H35789-001	H35789-001	4
MIC5166_DFN-IC,H55101-001	H55101-001	4
MOSFETN_1D3S_SOT5-IC,G68777-001	G68777-001	3
MOSFET_N_LCC3-BSZ019N03LS,NFETA	G26762-001	4
MTG_KEYHOLE_TH-EMPTY,NA	NA	7
NB3W1200L_LCC-IC,H13585-001	H13585-001	1
NC7SB3157_SMLF-IC,C99406-001	C99406-001	3
NCP3232L_SM-IC,H86355-001	H86355-001	4
NPN_DUAL_SSOPLF-MBT3904,EMPTY,A	C52264-001	1
NPN_DUAL_SSOPLF-MBT3904,XSTR,CA	C52264-001	1
NPN_SM-MMBT3904,IC,C52245-001	C52245-001	7
OSC_C_6P10-156.25MHZ,OSC,G6383A	G63831-004	2
OSC_C_SM4-24MHZ,OSC,D34520-021	D34520-021	1
PCA9515ADGKR-1-GP_DISCRET-G5-PA		1
PCA9517_SM-IC,G77073-001-GND=GA	G77073-001	1
PCA9555PWRG4-GP_DISCRET-G5-PCAA		1
PCA9617_SSOP-IC,G81764-001-GNDA	G81764-001	4
PI3B3257A_TSSOPLF-IC,E16801-001	E16801-001	2
PI7C9X1172_QFN-IC,H66899-001	H66899-001	1
PNP_TO92-MPS2907,IC,G73554-001	G73554-001	2
PXE1110B_QFN-IC,H89187-001	H89187-001	3
PXE1610B_QFN-IC,H79206-001	H79206-001	2
PXM1310B_QFN-IC,H89186-001	H89186-001	4
RCC_DFX1940_ID4-EMPTY,N_A	N_A	4
RES_0402-0.0,5%,1/16W,CHIP,G21A	G21497-005	312
RES_0402-0.0,5%,1/16W,EMPTY,G2A	G21497-005	88
RES_0402-1.0,1%,1/16W,CHIP,G21A	G21796-090	24
RES_0402-1.00K,1%,1/16W,CHIP,GA	G21796-026	143
RES_0402-1.00K,1%,1/16W,EMPTY,A	G21796-026	23
RES_0402-1.0K,0.1%,1/16W,CHIP,A	G85996-004	8
RES_0402-1.0M,1%,1/16W,EMPTY,GA	G21796-021	5
RES_0402-1.37K,1%,1/16W,CHIP,GA	G21796-095	3
RES_0402-1.5K,1%,1/16W,CHIP,G2A	G21796-003	12
RES_0402-1.8K,1%,1/16W,CHIP,G2A	G21796-336	8
RES_0402-10.0,1%,1/16W,CHIP,G2A	G21796-066	42
RES_0402-10.0,1%,1/16W,EMPTY,GA	G21796-066	2
RES_0402-10.0K,1%,1/16W,CHIP,GA	G21796-016	105
RES_0402-10.0K,1%,1/16W,EMPTY,A	G21796-016	14
RES_0402-100.0,1%,1/16W,CHIP,GA	G21796-017	53
RES_0402-100.0,1%,1/16W,EMPTY,A	G21796-017	10
RES_0402-100.0K,1%,1/16W,CHIP,A	G21796-010	27
RES_0402-100.0K,1%,1/16W,CHIP,B	G21796-160	10
RES_0402-100.0K,1%,1/16W,EMPTYA	G21796-010	10
RES_0402-105.0K,1%,1/16W,CHIP,A	G21796-099	1
RES_0402-110,1%,1/16W,EMPTY,G2A	G21796-203	1
RES_0402-113,1%,1/16W,CHIP,G21A	G21796-341	1
RES_0402-11K,1%,1/16W,CHIP,G21A	G21796-220	1
RES_0402-12.1K,1%,1/16W,CHIP,GA	G21796-089	1
RES_0402-13K,1.0%,1/16W,CHIP,GA	G21796-221	2
RES_0402-15.0K,1%,1/16W,CHIP,GA	G21796-107	4
RES_0402-150.0,1%,1/16W,CHIP,GA	G21796-009	38
RES_0402-150.0K,1%,1/16W,CHIP,A	G21796-109	2
RES_0402-169,1.0%,1/16W,CHIP,GA	G21796-276	1
RES_0402-16K,1.0%,1/16W,CHIP,GA	G21796-317	2
RES_0402-2,1.0%,1/16W,CHIP,G21A	G21796-274	12
RES_0402-2.0K,1%,1/16W,CHIP,G2A	G21796-001	14
RES_0402-2.0K,1%,1/16W,EMPTY,GA	G21796-001	2
RES_0402-2.2,5%,1/16W,EMPTY,G2A	G21497-016	5
RES_0402-2.21K,1%,1/16W,CHIP,GA	G21796-112	14
RES_0402-2.26K,1.0%,1/16W,CHIPA	G21796-311	7
RES_0402-2.26K,1.0%,1/16W,EMPTA	G21796-311	13
RES_0402-2.67K,1%,1/16W,CHIP,GA	G21796-180	1
RES_0402-2.7K,1%,1/16W,CHIP,G2A	G21796-344	9
RES_0402-2.7K,1%,1/16W,EMPTY,GA	G21796-344	5
RES_0402-20.0,1%,1/16W,CHIP,G2A	G21796-173	70
RES_0402-20.0,1%,1/16W,EMPTY,GA	G21796-173	4
RES_0402-20.0K,1%,1/16W,CHIP,GA	G21796-040	8
RES_0402-20.0K,1%,1/16W,EMPTY,A	G21796-040	1
RES_0402-200.0,1%,1/16W,CHIP,GA	G21796-004	11
RES_0402-200.0K,1%,1/16W,CHIP,A	G21796-080	1
RES_0402-22.1,1.0%,1/16W,CHIP,A	G21796-250	34
RES_0402-221,1.0%,1/16W,CHIP,GA	G21796-271	10
RES_0402-23.2K,1%,1/16W,CHIP,GA	G21796-114	1
RES_0402-24.9K,1%,1/16W,CHIP,GA	G21796-254	1
RES_0402-240,1.0%,1/16W,CHIP,GA	G21796-294	20
RES_0402-240,1.0%,1/16W,EMPTY,A	G21796-294	18
RES_0402-249,0.1%,1/16W,CHIP,GA	G85996-031	2
RES_0402-249K,1.0%,1/16W,CHIP,A	G21796-189	1
RES_0402-27.4,1%,1/16W,CHIP,G2A	G21796-182	24
RES_0402-274K,1.0%,1/16W,CHIP,A	G21796-331	1
RES_0402-3.16K,1%,1/16W,CHIP,GA	G21796-043	7
RES_0402-3.32K,1%,1/16W,CHIP,GA	G21796-027	5
RES_0402-3.32K,1%,1/16W,EMPTY,A	G21796-027	3
RES_0402-3.3K,5%,1/16W,CHIP,G2A	G21497-013	2
RES_0402-3.48K,1.0%,1/16W,CHIPA	G21796-279	2
RES_0402-3.74K,1%,1/16W,CHIP,GA	G21796-059	1
RES_0402-301.0,1%,1/16W,CHIP,GA	G21796-076	1
RES_0402-33.0K,5%,1/16W,CHIP,GA	G21497-023	1
RES_0402-33.2,1%,1/16W,CHIP,G2A	G21796-074	93
RES_0402-33.2,1%,1/16W,EMPTY,GA	G21796-074	1
RES_0402-330,5%,1/16W,CHIP,G21A	G21497-028	2
RES_0402-348,1%,1/16W,CHIP,G21A	G21796-340	1
RES_0402-348,1%,1/16W,EMPTY,G2A	G21796-340	1
RES_0402-4.02K,1%,1/16W,CHIP,GA	G21796-082	8
RES_0402-4.75K,1%,1/16W,CHIP,GA	G21796-072	129
RES_0402-4.75K,1%,1/16W,EMPTY,A	G21796-072	37
RES_0402-4.99K,1%,1/16W,CHIP,GA	G21796-013	2
RES_0402-40.2K,1%,1/16W,CHIP,GA	G21796-133	1
RES_0402-42.2,1.0%,1/16W,EMPTYA	G21796-259	24
RES_0402-470.0,5%,1/16W,CHIP,GA	G21497-024	1
RES_0402-475.0,1%,1/16W,CHIP,GA	G21796-077	2
RES_0402-49.9,1%,1/16W,CHIP,G2A	G21796-047	60
RES_0402-49.9,1%,1/16W,EMPTY,GA	G21796-047	5
RES_0402-49.9K,1%,1/16W,CHIP,GA	G21796-048	2
RES_0402-5.11K,1%,1/16W,CHIP,GA	G21796-140	7
RES_0402-5.36K,1.0%,1/16W,CHIPA	G21796-297	2
RES_0402-51,5.0%,1/16W,CHIP,G2A	G21497-048	4
RES_0402-51.1,1.0%,1/16W,CHIP,A	G21796-208	11
RES_0402-560,5%,1/16W,CHIP,G21A	G21497-062	1
RES_0402-6.19K,1%,1/16W,CHIP,GA	G21796-161	2
RES_0402-6.34K,1%,1/16W,CHIP,GA	G21796-146	5
RES_0402-63.4K,1.0%,1/16W,CHIPA	G21796-327	1
RES_0402-64.9,1.0%,1/16W,CHIP,A	G21796-298	5
RES_0402-64.9K,1%,1/16W,CHIP,GA	G21796-148	1
RES_0402-665,1.0%,1/16W,CHIP,GA	G21796-235	18
RES_0402-68.1K,1%,1/16W,EMPTY,A	G21796-187	24
RES_0402-69.8K,1%,1/16W,CHIP,GA	G21796-007	1
RES_0402-7.5K,1%,1/16W,CHIP,G2A	G21796-177	1
RES_0402-7.87K,1.0%,1/16W,CHIPA	G21796-242	8
RES_0402-75,1.0%,1/16W,CHIP,G2A	G21796-267	6
RES_0402-75K,1%,1/16W,CHIP,G21A	G21796-224	1
RES_0402-8.06K,1%,1/16W,CHIP,GA	G21796-078	3
RES_0402-8.2K,1%,1/16W,CHIP,G2A	G21796-345	4
RES_0402-8.2K,1%,1/16W,EMPTY,GA	G21796-345	1
RES_0402-90.9,1%,1/16W,CHIP,G2A	G21796-365	8
RES_0402-90.9K,1%,1/16W,CHIP,GA	G21796-058	2
RES_0603-0,5.0%,1/10W,CHIP,G22A	G22178-002	3
RES_0603-0,5.0%,1/10W,EMPTY,G2A	G22178-002	1
RES_0603-10.0,1%,1/10W,CHIP,G2A	G22026-041	2
RES_0603-100.0,1%,1/10W,CHIP,GA	G22026-038	2
RES_0603-100.0K,1%,1/10W,CHIP,A	G22026-050	2
RES_0603-10M,1.0%,1/10W,CHIP,GA	G22026-112	1
RES_0603-120.0,1%,1/10W,CHIP,GA	G22026-003	8
RES_0603-2.2,1.0%,1/10W,CHIP,GA	G22026-127	5
RES_0603-200K,0.1%,1/10W,CHIP,A	G22369-010	1
RES_0603-475.0,1%,1/10W,CHIP,GA	G22026-030	1
RES_0805-0.0,5%,1/8W,CHIP,G221A	G22179-004	1
RES_1206-0.002,1%,1W,CHIP,G521A	G52199-004	4
RES_2010-0.001,1%,1W,CHIP,E309A	E30969-002	2
RES_PWR_6PAD-0.001,1%,3W,CHIP,A	E74391-005	2
RT8240_QFN-IC,H66262-001	H66262-001	1
RT9059_DFN-IC,H65765-001	H65765-001	4
SC1U16V3KX-2GP_SMD-BCG-SC1U16VA		2
SC22P50V2JN-4GP_SMD-BCG-SC22P5A		2
SC2K2P50V3KX-GP_SMD-BCG6-SC2K2A		24
SC4D7U10V3KX-GP_SMD-BCG-SC4D7UA		11
SCD1U16V2KX-3GP_SMD-BCG-SCD1U1A		12
SCONN10_C12536004_SMLF-CONN,C1A	C12536-004	1
SCONN11_H67026001_SM-CONN,H670A	H67026-001	1
SCONN120_A28699018_SM-SCONN,A2A	A28699-018	1
SCONN120_H61426002_SM-CONN,H61A	H61426-002	4
SCONN200_H68296001_SM-CONN,H68A	H68296-001	1
SCONN24_H46321001_SM-SCONN,H46A	H46321-001	1
SCONN288_H44441003_PIP-SCONN,HA	H44441-003	12
SCONN288_H44441004_PIP-SCONN,HA	H44441-004	12
SCONN3_D53458001_SM-EMPTY,D534A	D53458-001	1
SCONN60_C21100002_SMLF-CONN,C2A	C21100-002	1
SCONN64_H87568002_A_SMT-CONN,HA	H87568-002	1
SCONN75K_H17033002_SMT1-SCONN,A	H17033-002	1
SCONN80_E67482007_SM-CONN,E674A	E67482-007	1
SHUNT_SH0201-EMPTY,N_A	N_A	16
SKX_EXT_B_BGA1-IC,TBD	TBD	2
SLG55021_SM-IC,G56246-001	G56246-001	4
SMC-CONN60A-22-GP_CONN-G7-SMC-A		1
SNLABEL_A_LABEL-EMPTY,N_A	N_A	5
SOCKET_P_MECH_A_LEFT-P0,PLASTIA	H37604-201	2
SOCKET_P_MECH_A_RIGHT-P0,PLASTA	H37604-101	2
SPRINGVILLE_SM1-IC,G47144-004	G47144-004	1
STANDOFF_TH1-SO,H72821-001	H72821-001	1
SWITCH_D37771002_SM-IC,D37771-A	D37771-002	1
SWITCH_D90553001_SMLF-IC,D9055A	D90553-001	1
SW_H67881001_SM-IC,H67881-001	H67881-001	1
TMP421_TSSOP-IC,G62962-001	G62962-001	2
TPS2061_SM-IC,H66405-001	H66405-001	1
TPS3700_SM-IC,H69492-001	H69492-001	4
TPS54821_LCC-IC,H63269-001	H63269-001	1
TTL08_QFN15-74LVC08A,IC,D90404B	D90404-001	1
TTL1G07_A_SOP-74LVC1G07,IC,C88B	C88419-001	9
TTL1G08_SOTLF-NC7SZ08,IC,D1032B	D10321-001	4
TTL1G08_SOTLF-NC7SZ08,IC,D1032C	D10321-001	1
TTL1G126_A_SOT-74HC1G126,IC,A7B	A79322-001	5
TTL1G32_A_SOT-74LVC1G32,IC,E60B	E60229-001	2
TTL1G86_SOTLF-74AHCT1G86,IC,D3B	D39848-001	1
TTL2G07_SOT23LF-74LVC2G07,IC,DB	D22707-001	2
TTL2G14_SMLF-74LVC2G14,IC,D184B	D18476-001	3
TTL3126_QFNLF-74CBTLV3126,IC,DB	D18317-001	2
VERT_BATT_3PIN_PIP-3PVERT,C686A	C68619-005	1
W25Q128_SKT16-IC,H12709-001	H12709-001	1
W25Q256_XSOI-IC,H25002-001	H25002-001	3
ZENER_SM-13V,IC,H69095-001	H69095-001	1

Total                                    4385
